# S9S_MB_2U (Grand Teton) — schematic netlist excerpt (pin names and nets, part order shuffled) for the footprints in the layout excerpt that follows; sources: Cadence DE-HDL packaged netlist, KiCad conversion of 03242023_DA0F0TMBIJ0_F0T_Motherboard_J_brd_V01_OCP.brd

J22  SCONN288_ADR50017P087CC  SCONN288_ADR50017-P087CC IO  pkg DDR288S_1-1VXB  page 103
  VIN_BULK0  = P12V_S3_AUX_CPU1_NVDIMM
  RFU0  = TP_CHC_CPU1_DIMM2_FRU_0
  VIN_MGMT  = P3V3_AUX
  HSCL  = I3C_SPD_DDRABCD_CPU1_LVC1_SCL_5
  HSDA  = I3C_SPD_DDRABCD_CPU1_LVC1_SDA
  VSS0  = GND
  DQ0_A  = M_C_CPU1_SA_DQ<0>
  VSS1  = GND
  DQ1_A  = M_C_CPU1_SA_DQ<1>
  VSS2  = GND
  DQS0_A_T  = M_C_CPU1_SA_DQS_DP<0>
  DQS0_A_C  = M_C_CPU1_SA_DQS_DN<0>
  VSS3  = GND
  DQ4_A  = M_C_CPU1_SA_DQ<4>
  VSS4  = GND
  DQ5_A  = M_C_CPU1_SA_DQ<5>
  VSS5  = GND
  DQ8_A  = M_C_CPU1_SA_DQ<8>
  VSS6  = GND
  DQ9_A  = M_C_CPU1_SA_DQ<9>
  VSS7  = GND
  DQS1_A_T  = M_C_CPU1_SA_DQS_DP<1>
  DQS1_A_C  = M_C_CPU1_SA_DQS_DN<1>
  VSS8  = GND
  DQ12_A  = M_C_CPU1_SA_DQ<12>
  VSS9  = GND
  DQ13_A  = M_C_CPU1_SA_DQ<13>
  VSS10  = GND
  DQ16_A  = M_C_CPU1_SA_DQ<16>
  VSS11  = GND
  DQ17_A  = M_C_CPU1_SA_DQ<17>
  VSS12  = GND
  DQS2_A_T  = M_C_CPU1_SA_DQS_DP<2>
  DQS2_A_C  = M_C_CPU1_SA_DQS_DN<2>
  VSS13  = GND
  DQ20_A  = M_C_CPU1_SA_DQ<20>
  VSS14  = GND
  DQ21_A  = M_C_CPU1_SA_DQ<21>
  VSS15  = GND
  DQ24_A  = M_C_CPU1_SA_DQ<24>
  VSS16  = GND
  DQ25_A  = M_C_CPU1_SA_DQ<25>
  VSS17  = GND
  DQS3_A_T  = M_C_CPU1_SA_DQS_DP<3>
  DQS3_A_C  = M_C_CPU1_SA_DQS_DN<3>
  VSS18  = GND
  DQ28_A  = M_C_CPU1_SA_DQ<28>
  VSS19  = GND
  DQ29_A  = M_C_CPU1_SA_DQ<29>
  VSS20  = GND
  CB0_A  = M_C_CPU1_SA_CB<0>
  VSS21  = GND
  CB1_A  = M_C_CPU1_SA_CB<1>
  VSS22  = GND
  DQS4_A_T  = M_C_CPU1_SA_DQS_DP<4>
  DQS4_A_C  = M_C_CPU1_SA_DQS_DN<4>
  VSS23  = GND
  CB4_A  = M_C_CPU1_SA_CB<4>
  VSS24  = GND
  CB5_A  = M_C_CPU1_SA_CB<5>
  VSS25  = GND
  ALERT_N  = M_C_CPU1_ALERT_N
  VSS26  = GND
  CS0_A_N  = M_C_CPU1_SA_CS_N<2>
  VSS27  = GND
  CA0_A  = M_C_CPU1_SA_CA<0>
  VSS28  = GND
  CA2_A  = M_C_CPU1_SA_CA<2>
  VSS29  = GND
  CA4_A  = M_C_CPU1_SA_CA<4>
  VSS30  = GND
  CA6_A  = M_C_CPU1_SA_CA<6>
  VSS31  = GND
  PAR_A  = M_C_CPU1_SA_PAR
  VSS32  = GND
  CA0_B  = M_C_CPU1_SB_CA<0>
  VSS33  = GND
  CA2_B  = M_C_CPU1_SB_CA<2>
  VSS34  = GND
  CA4_B  = M_C_CPU1_SB_CA<4>
  VSS35  = GND
  CA6_B  = M_C_CPU1_SB_CA<6>
  VSS36  = GND
  CS0_B_N  = M_C_CPU1_SB_CS_N<2>
  VSS37  = GND
  \lbd||rsp_a_n\  = M_C_CPU1_SA_RSP<1>
  \lbs||rsp_b_n\  = M_C_CPU1_SB_RSP<1>
  VSS38  = GND
  CB4_B  = M_C_CPU1_SB_CB<4>
  VSS39  = GND
  CB5_B  = M_C_CPU1_SB_CB<5>
  VSS40  = GND
  \dqs9_b_t||tdqs9_b_t||dbi4_b_n\  = M_C_CPU1_SB_DQS_DP<9>
  \dqs9_b_c||tdqs9_b_c\  = M_C_CPU1_SB_DQS_DN<9>
  VSS41  = GND
  CB0_B  = M_C_CPU1_SB_CB<0>
  VSS42  = GND
  CB1_B  = M_C_CPU1_SB_CB<1>
  VSS43  = GND
  DQ0_B  = M_C_CPU1_SB_DQ<0>
  VSS44  = GND
  DQ1_B  = M_C_CPU1_SB_DQ<1>
  VSS45  = GND
  DQS0_B_T  = M_C_CPU1_SB_DQS_DP<0>
  DQS0_B_C  = M_C_CPU1_SB_DQS_DN<0>
  VSS46  = GND
  DQ4_B  = M_C_CPU1_SB_DQ<4>
  VSS47  = GND
  DQ5_B  = M_C_CPU1_SB_DQ<5>
  VSS48  = GND
  DQ8_B  = M_C_CPU1_SB_DQ<8>
  VSS49  = GND
  DQ9_B  = M_C_CPU1_SB_DQ<9>
  VSS50  = GND
  DQS1_B_T  = M_C_CPU1_SB_DQS_DP<1>
  DQS1_B_C  = M_C_CPU1_SB_DQS_DN<1>
  VSS51  = GND
  DQ12_B  = M_C_CPU1_SB_DQ<12>
  VSS52  = GND
  DQ13_B  = M_C_CPU1_SB_DQ<13>
  VSS53  = GND
  DQ16_B  = M_C_CPU1_SB_DQ<16>
  VSS54  = GND
  DQ17_B  = M_C_CPU1_SB_DQ<17>
  VSS55  = GND
  DQS2_B_T  = M_C_CPU1_SB_DQS_DP<2>
  DQS2_B_C  = M_C_CPU1_SB_DQS_DN<2>
  VSS56  = GND
  DQ20_B  = M_C_CPU1_SB_DQ<20>
  VSS57  = GND
  DQ21_B  = M_C_CPU1_SB_DQ<21>
  VSS58  = GND
  DQ24_B  = M_C_CPU1_SB_DQ<24>
  VSS59  = GND
  DQ25_B  = M_C_CPU1_SB_DQ<25>
  VSS60  = GND
  DQS3_B_T  = M_C_CPU1_SB_DQS_DP<3>
  DQS3_B_C  = M_C_CPU1_SB_DQS_DN<3>
  VSS61  = GND
  DQ28_B  = M_C_CPU1_SB_DQ<28>
  VSS62  = GND
  DQ29_B  = M_C_CPU1_SB_DQ<29>
  VSS63  = GND
  RFU1  = TP_CHC_CPU1_DIMM2_FRU_1
  VIN_BULK1  = P12V_S3_AUX_CPU1_NVDIMM
  VIN_BULK2  = P12V_S3_AUX_CPU1_NVDIMM
  \pwr_good||fail_n\  = PWRGD_CHC_CPU1_DIMM2
  HSA  = PD_CHC_CPU1_DIMM2_SAA
  RFU2  = TP_CHC_CPU1_DIMM2_FRU_2
  RFU3  = TP_CHC_CPU1_DIMM2_FRU_3
  VSS64  = GND
  DQ2_A  = M_C_CPU1_SA_DQ<2>
  VSS65  = GND
  DQ3_A  = M_C_CPU1_SA_DQ<3>
  VSS66  = GND
  \dqs5_a_c||tdqs5_a_c||dqs5_a_t||tdqs5_a_t\  = M_C_CPU1_SA_DQS_DN<5>
  \dqs5_a_t||tdqs5_a_t\  = M_C_CPU1_SA_DQS_DP<5>
  VSS67  = GND
  DQ6_A  = M_C_CPU1_SA_DQ<6>
  VSS68  = GND
  DQ7_A  = M_C_CPU1_SA_DQ<7>
  VSS69  = GND
  DQ10_A  = M_C_CPU1_SA_DQ<10>
  VSS70  = GND
  DQ11_A  = M_C_CPU1_SA_DQ<11>
  VSS71  = GND
  \dqs6_a_c||tdqs6_a_c||dqs6_a_t||tdqs6_a_t\  = M_C_CPU1_SA_DQS_DN<6>
  \dqs6_a_t||tdqs6_a_t\  = M_C_CPU1_SA_DQS_DP<6>
  VSS72  = GND
  DQ14_A  = M_C_CPU1_SA_DQ<14>
  VSS73  = GND
  DQ15_A  = M_C_CPU1_SA_DQ<15>
  VSS74  = GND
  DQ18_A  = M_C_CPU1_SA_DQ<18>
  VSS75  = GND
  DQ19_A  = M_C_CPU1_SA_DQ<19>
  VSS76  = GND
  \dqs7_a_c||tdqs7_a_c\  = M_C_CPU1_SA_DQS_DN<7>
  \dqs7_a_t||tdqs7_a_t\  = M_C_CPU1_SA_DQS_DP<7>
  VSS77  = GND
  DQ22_A  = M_C_CPU1_SA_DQ<22>
  VSS78  = GND
  DQ23_A  = M_C_CPU1_SA_DQ<23>
  VSS79  = GND
  DQ26_A  = M_C_CPU1_SA_DQ<26>
  VSS80  = GND
  DQ27_A  = M_C_CPU1_SA_DQ<27>
  VSS81  = GND
  \dqs8_a_c||tdqs8_a_c\  = M_C_CPU1_SA_DQS_DN<8>
  \dqs8_a_t||tdqs8_a_t\  = M_C_CPU1_SA_DQS_DP<8>
  VSS82  = GND
  DQ30_A  = M_C_CPU1_SA_DQ<30>
  VSS83  = GND
  DQ31_A  = M_C_CPU1_SA_DQ<31>
  VSS84  = GND
  CB2_A  = M_C_CPU1_SA_CB<2>
  VSS85  = GND
  CB3_A  = M_C_CPU1_SA_CB<3>
  VSS86  = GND
  \dqs9_a_c||tdqs9_a_c\  = M_C_CPU1_SA_DQS_DN<9>
  \dqs9_a_t||tdqs9_a_t\  = M_C_CPU1_SA_DQS_DP<9>
  VSS87  = GND
  CB6_A  = M_C_CPU1_SA_CB<6>
  VSS88  = GND
  CB7_A  = M_C_CPU1_SA_CB<7>
  VSS89  = GND
  RESET_N  = RST_M_CD_CPU1_FPGA_N
  VSS90  = GND
  CS1_A_N  = M_C_CPU1_SA_CS_N<3>
  VSS91  = GND
  CA1_A  = M_C_CPU1_SA_CA<1>
  VSS92  = GND
  CA3_A  = M_C_CPU1_SA_CA<3>
  VSS93  = GND
  CA5_A  = M_C_CPU1_SA_CA<5>
  VSS94  = GND
  CK_T  = M_C_CPU1_CLK_DP<1>
  CK_C  = M_C_CPU1_CLK_DN<1>
  VSS95  = GND
  RFU4  = TP_CHC_CPU1_DIMM2_FRU_4
  CA1_B  = M_C_CPU1_SB_CA<1>
  VSS96  = GND
  CA3_B  = M_C_CPU1_SB_CA<3>
  VSS97  = GND
  CA5_B  = M_C_CPU1_SB_CA<5>
  VSS98  = GND
  PAR_B  = M_C_CPU1_SB_PAR
  VSS99  = GND
  CS1_B_N  = M_C_CPU1_SB_CS_N<3>
  VSS100  = GND
  RFU5  = TP_CHC_CPU1_DIMM2_FRU_5
  RFU6  = TP_CHC_CPU1_DIMM2_FRU_6
  VSS101  = GND
  CB6_B  = M_C_CPU1_SB_CB<6>
  VSS102  = GND
  CB7_B  = M_C_CPU1_SB_CB<7>
  VSS103  = GND
  DQS4_B_C  = M_C_CPU1_SB_DQS_DN<4>
  DQS4_B_T  = M_C_CPU1_SB_DQS_DP<4>
  VSS104  = GND
  CB2_B  = M_C_CPU1_SB_CB<2>
  VSS105  = GND
  CB3_B  = M_C_CPU1_SB_CB<3>
  VSS106  = GND
  DQ2_B  = M_C_CPU1_SB_DQ<2>
  VSS107  = GND
  DQ3_B  = M_C_CPU1_SB_DQ<3>
  VSS108  = GND
  \dqs5_b_c||tdqs5_b_c\  = M_C_CPU1_SB_DQS_DN<5>
  \dqs5_b_t||tdqs5_b_t\  = M_C_CPU1_SB_DQS_DP<5>
  VSS109  = GND
  DQ6_B  = M_C_CPU1_SB_DQ<6>
  VSS110  = GND
  DQ7_B  = M_C_CPU1_SB_DQ<7>
  VSS111  = GND
  DQ10_B  = M_C_CPU1_SB_DQ<10>
  VSS112  = GND
  DQ11_B  = M_C_CPU1_SB_DQ<11>
  VSS113  = GND
  \dqs6_b_c||tdqs6_b_c\  = M_C_CPU1_SB_DQS_DN<6>
  \dqs6_b_t||tdqs6_b_t\  = M_C_CPU1_SB_DQS_DP<6>
  VSS114  = GND
  DQ14_B  = M_C_CPU1_SB_DQ<14>
  VSS115  = GND
  DQ15_B  = M_C_CPU1_SB_DQ<15>
  VSS116  = GND
  DQ18_B  = M_C_CPU1_SB_DQ<18>
  VSS117  = GND
  DQ19_B  = M_C_CPU1_SB_DQ<19>
  VSS118  = GND
  \dqs7_b_c||tdqs7_b_c\  = M_C_CPU1_SB_DQS_DN<7>
  \dqs7_b_t||tdqs7_b_t\  = M_C_CPU1_SB_DQS_DP<7>
  VSS119  = GND
  DQ22_B  = M_C_CPU1_SB_DQ<22>
  VSS120  = GND
  DQ23_B  = M_C_CPU1_SB_DQ<23>
  VSS121  = GND
  DQ26_B  = M_C_CPU1_SB_DQ<26>
  VSS122  = GND
  DQ27_B  = M_C_CPU1_SB_DQ<27>
  VSS123  = GND
  \dqs8_b_c||tdqs8_b_c\  = M_C_CPU1_SB_DQS_DN<8>
  \dqs8_b_t||tdqs8_b_t\  = M_C_CPU1_SB_DQS_DP<8>
  VSS124  = GND
  DQ30_B  = M_C_CPU1_SB_DQ<30>
  VSS125  = GND
  DQ31_B  = M_C_CPU1_SB_DQ<31>
  VSS126  = GND
  G1  = GND
  G2  = GND
  G3  = GND

(kicad_pcb
	(version 20260206)
	(generator "pcbnew")
	(generator_version "10.0")
	(general
		(thickness 1.6)
		(legacy_teardrops no)
	)
	(paper "A4")
	(title_block
		(title "03242023_DA0F0TMBIJ0_F0T_Motherboard_J_brd_V01_OCP.brd")
		(comment 1 "Grand Teton / footprint 501 of 6105 (J22), pads 92-137 of 291")
	)
	(layers
		(0 "F.Cu" signal "TOP")
		(4 "In1.Cu" signal "GND")
		(6 "In2.Cu" signal "IN1")
		(8 "In3.Cu" signal "GND1")
		(10 "In4.Cu" signal "IN2")
		(12 "In5.Cu" signal "GND2")
		(14 "In6.Cu" signal "IN3")
		(16 "In7.Cu" signal "GND3")
		(18 "In8.Cu" signal "VCC")
		(20 "In9.Cu" signal "VCC1")
		(22 "In10.Cu" signal "GND4")
		(24 "In11.Cu" signal "IN4")
		(26 "In12.Cu" signal "GND5")
		(28 "In13.Cu" signal "IN5")
		(30 "In14.Cu" signal "GND6")
		(32 "In15.Cu" signal "IN6")
		(34 "In16.Cu" signal "GND7")
		(2 "B.Cu" signal "BOTTOM")
		(9 "F.Adhes" user "F.Adhesive")
		(11 "B.Adhes" user "B.Adhesive")
		(13 "F.Paste" user "Package Geometry/Pastemask Top")
		(15 "B.Paste" user "Package Geometry/Pastemask Bottom")
		(5 "F.SilkS" user "Ref Des/Silkscreen Top")
		(7 "B.SilkS" user "Ref Des/Silkscreen Bottom")
		(1 "F.Mask" user "Board Geometry/Soldermask Top")
		(3 "B.Mask" user "Board Geometry/Soldermask Bottom")
		(17 "Dwgs.User" user "User.Drawings")
		(19 "Cmts.User" user "User.Comments")
		(21 "Eco1.User" user "User.Eco1")
		(23 "Eco2.User" user "User.Eco2")
		(25 "Edge.Cuts" user "Board Geometry/Outline")
		(27 "Margin" user)
		(31 "F.CrtYd" user "Package Geometry/Place Bound Top")
		(29 "B.CrtYd" user "Package Geometry/Place Bound Bottom")
		(35 "F.Fab" user "Ref Des/Assembly Top")
		(33 "B.Fab" user "Ref Des/Assembly Bottom")
	)
	(footprint ""
		(layer "F.Cu")
		(at 32.82188 -258.091686)
		(property "Reference" "J22"
			(at -1.420622 -81.912714 0)
			(unlocked yes)
			(layer "F.SilkS")
			(effects
				(font
					(size 0.7874 0.5842)
					(thickness 0.1524)
				)
				(justify left)
			)
		)
		(property "Value" ""
			(at 0 0 0)
			(layer "F.Fab")
			(effects
				(font
					(size 1.27 1.27)
				)
			)
		)
		(duplicate_pad_numbers_are_jumpers no)
		(pad "92" smd rect
			(at -2.050034 19.12493 270)
			(size 0.519938 1.4986)
			(layers "F.Cu" "F.Mask" "F.Paste")
			(net "GND")
		)
		(pad "93" smd rect
			(at -2.050034 19.975068 270)
			(size 0.519938 1.4986)
			(layers "F.Cu" "F.Mask" "F.Paste")
			(net "M_C_CPU1_SB_DQS_DP<9>")
		)
		(pad "94" smd rect
			(at -2.050034 20.824952 270)
			(size 0.519938 1.4986)
			(layers "F.Cu" "F.Mask" "F.Paste")
			(net "M_C_CPU1_SB_DQS_DN<9>")
		)
		(pad "95" smd rect
			(at -2.050034 21.67509 270)
			(size 0.519938 1.4986)
			(layers "F.Cu" "F.Mask" "F.Paste")
			(net "GND")
		)
		(pad "96" smd rect
			(at -2.050034 22.524974 270)
			(size 0.519938 1.4986)
			(layers "F.Cu" "F.Mask" "F.Paste")
			(net "M_C_CPU1_SB_CB<0>")
		)
		(pad "97" smd rect
			(at -2.050034 23.375112 270)
			(size 0.519938 1.4986)
			(layers "F.Cu" "F.Mask" "F.Paste")
			(net "GND")
		)
		(pad "98" smd rect
			(at -2.050034 24.224996 270)
			(size 0.519938 1.4986)
			(layers "F.Cu" "F.Mask" "F.Paste")
			(net "M_C_CPU1_SB_CB<1>")
		)
		(pad "99" smd rect
			(at -2.050034 25.07488 270)
			(size 0.519938 1.4986)
			(layers "F.Cu" "F.Mask" "F.Paste")
			(net "GND")
		)
		(pad "100" smd rect
			(at -2.050034 25.925018 270)
			(size 0.519938 1.4986)
			(layers "F.Cu" "F.Mask" "F.Paste")
			(net "M_C_CPU1_SB_DQ<0>")
		)
		(pad "101" smd rect
			(at -2.050034 26.774902 270)
			(size 0.519938 1.4986)
			(layers "F.Cu" "F.Mask" "F.Paste")
			(net "GND")
		)
		(pad "102" smd rect
			(at -2.050034 27.62504 270)
			(size 0.519938 1.4986)
			(layers "F.Cu" "F.Mask" "F.Paste")
			(net "M_C_CPU1_SB_DQ<1>")
		)
		(pad "103" smd rect
			(at -2.050034 28.474924 270)
			(size 0.519938 1.4986)
			(layers "F.Cu" "F.Mask" "F.Paste")
			(net "GND")
		)
		(pad "104" smd rect
			(at -2.050034 29.325062 270)
			(size 0.519938 1.4986)
			(layers "F.Cu" "F.Mask" "F.Paste")
			(net "M_C_CPU1_SB_DQS_DP<0>")
		)
		(pad "105" smd rect
			(at -2.050034 30.174946 270)
			(size 0.519938 1.4986)
			(layers "F.Cu" "F.Mask" "F.Paste")
			(net "M_C_CPU1_SB_DQS_DN<0>")
		)
		(pad "106" smd rect
			(at -2.050034 31.025084 270)
			(size 0.519938 1.4986)
			(layers "F.Cu" "F.Mask" "F.Paste")
			(net "GND")
		)
		(pad "107" smd rect
			(at -2.050034 31.874968 270)
			(size 0.519938 1.4986)
			(layers "F.Cu" "F.Mask" "F.Paste")
			(net "M_C_CPU1_SB_DQ<4>")
		)
		(pad "108" smd rect
			(at -2.050034 32.725106 270)
			(size 0.519938 1.4986)
			(layers "F.Cu" "F.Mask" "F.Paste")
			(net "GND")
		)
		(pad "109" smd rect
			(at -2.050034 33.57499 270)
			(size 0.519938 1.4986)
			(layers "F.Cu" "F.Mask" "F.Paste")
			(net "M_C_CPU1_SB_DQ<5>")
		)
		(pad "110" smd rect
			(at -2.050034 34.425128 270)
			(size 0.519938 1.4986)
			(layers "F.Cu" "F.Mask" "F.Paste")
			(net "GND")
		)
		(pad "111" smd rect
			(at -2.050034 35.275012 270)
			(size 0.519938 1.4986)
			(layers "F.Cu" "F.Mask" "F.Paste")
			(net "M_C_CPU1_SB_DQ<8>")
		)
		(pad "112" smd rect
			(at -2.050034 36.124896 270)
			(size 0.519938 1.4986)
			(layers "F.Cu" "F.Mask" "F.Paste")
			(net "GND")
		)
		(pad "113" smd rect
			(at -2.050034 36.975034 270)
			(size 0.519938 1.4986)
			(layers "F.Cu" "F.Mask" "F.Paste")
			(net "M_C_CPU1_SB_DQ<9>")
		)
		(pad "114" smd rect
			(at -2.050034 37.824918 270)
			(size 0.519938 1.4986)
			(layers "F.Cu" "F.Mask" "F.Paste")
			(net "GND")
		)
		(pad "115" smd rect
			(at -2.050034 38.675056 270)
			(size 0.519938 1.4986)
			(layers "F.Cu" "F.Mask" "F.Paste")
			(net "M_C_CPU1_SB_DQS_DP<1>")
		)
		(pad "116" smd rect
			(at -2.050034 39.52494 270)
			(size 0.519938 1.4986)
			(layers "F.Cu" "F.Mask" "F.Paste")
			(net "M_C_CPU1_SB_DQS_DN<1>")
		)
		(pad "117" smd rect
			(at -2.050034 40.375078 270)
			(size 0.519938 1.4986)
			(layers "F.Cu" "F.Mask" "F.Paste")
			(net "GND")
		)
		(pad "118" smd rect
			(at -2.050034 41.224962 270)
			(size 0.519938 1.4986)
			(layers "F.Cu" "F.Mask" "F.Paste")
			(net "M_C_CPU1_SB_DQ<12>")
		)
		(pad "119" smd rect
			(at -2.050034 42.0751 270)
			(size 0.519938 1.4986)
			(layers "F.Cu" "F.Mask" "F.Paste")
			(net "GND")
		)
		(pad "120" smd rect
			(at -2.050034 42.924984 270)
			(size 0.519938 1.4986)
			(layers "F.Cu" "F.Mask" "F.Paste")
			(net "M_C_CPU1_SB_DQ<13>")
		)
		(pad "121" smd rect
			(at -2.050034 43.775122 270)
			(size 0.519938 1.4986)
			(layers "F.Cu" "F.Mask" "F.Paste")
			(net "GND")
		)
		(pad "122" smd rect
			(at -2.050034 44.625006 270)
			(size 0.519938 1.4986)
			(layers "F.Cu" "F.Mask" "F.Paste")
			(net "M_C_CPU1_SB_DQ<16>")
		)
		(pad "123" smd rect
			(at -2.050034 45.47489 270)
			(size 0.519938 1.4986)
			(layers "F.Cu" "F.Mask" "F.Paste")
			(net "GND")
		)
		(pad "124" smd rect
			(at -2.050034 46.325028 270)
			(size 0.519938 1.4986)
			(layers "F.Cu" "F.Mask" "F.Paste")
			(net "M_C_CPU1_SB_DQ<17>")
		)
		(pad "125" smd rect
			(at -2.050034 47.174912 270)
			(size 0.519938 1.4986)
			(layers "F.Cu" "F.Mask" "F.Paste")
			(net "GND")
		)
		(pad "126" smd rect
			(at -2.050034 48.02505 270)
			(size 0.519938 1.4986)
			(layers "F.Cu" "F.Mask" "F.Paste")
			(net "M_C_CPU1_SB_DQS_DP<2>")
		)
		(pad "127" smd rect
			(at -2.050034 48.874934 270)
			(size 0.519938 1.4986)
			(layers "F.Cu" "F.Mask" "F.Paste")
			(net "M_C_CPU1_SB_DQS_DN<2>")
		)
		(pad "128" smd rect
			(at -2.050034 49.725072 270)
			(size 0.519938 1.4986)
			(layers "F.Cu" "F.Mask" "F.Paste")
			(net "GND")
		)
		(pad "129" smd rect
			(at -2.050034 50.574956 270)
			(size 0.519938 1.4986)
			(layers "F.Cu" "F.Mask" "F.Paste")
			(net "M_C_CPU1_SB_DQ<20>")
		)
		(pad "130" smd rect
			(at -2.050034 51.425094 270)
			(size 0.519938 1.4986)
			(layers "F.Cu" "F.Mask" "F.Paste")
			(net "GND")
		)
		(pad "131" smd rect
			(at -2.050034 52.274978 270)
			(size 0.519938 1.4986)
			(layers "F.Cu" "F.Mask" "F.Paste")
			(net "M_C_CPU1_SB_DQ<21>")
		)
		(pad "132" smd rect
			(at -2.050034 53.125116 270)
			(size 0.519938 1.4986)
			(layers "F.Cu" "F.Mask" "F.Paste")
			(net "GND")
		)
		(pad "133" smd rect
			(at -2.050034 53.975 270)
			(size 0.519938 1.4986)
			(layers "F.Cu" "F.Mask" "F.Paste")
			(net "M_C_CPU1_SB_DQ<24>")
		)
		(pad "134" smd rect
			(at -2.050034 54.824884 270)
			(size 0.519938 1.4986)
			(layers "F.Cu" "F.Mask" "F.Paste")
			(net "GND")
		)
		(pad "135" smd rect
			(at -2.050034 55.675022 270)
			(size 0.519938 1.4986)
			(layers "F.Cu" "F.Mask" "F.Paste")
			(net "M_C_CPU1_SB_DQ<25>")
		)
		(pad "136" smd rect
			(at -2.050034 56.524906 270)
			(size 0.519938 1.4986)
			(layers "F.Cu" "F.Mask" "F.Paste")
			(net "GND")
		)
		(pad "137" smd rect
			(at -2.050034 57.375044 270)
			(size 0.519938 1.4986)
			(layers "F.Cu" "F.Mask" "F.Paste")
			(net "M_C_CPU1_SB_DQS_DP<3>")
		)
	)
)
